# S9S_MB_2U (Grand Teton) — schematic parts with pin connectivity, parts 5001–5153 of 6093; source: Cadence DE-HDL packaged netlist (pstxprt.dat, pstxnet.dat, pstchip.dat)

R3512  Q_RES  100K 1% EMPTY  pkg 0402LF  page 148 : 1 = P3V3_AUX ; 2 = FM_GPU_PWRGD
R3513  Q_RES  54.9K 1% CHIP  pkg 0402LF  page 148 : 1 = FM_GPU_PWRGD ; 2 = GND
R3514  Q_RES  54.9K 1% CHIP  pkg 0402LF  page 148 : 1 = P3V3_AUX ; 2 = FM_SMB_2_ALERT_GPU_N
R3515  Q_RES  49.9 1% CHIP  pkg 0402LF  page 149 : 1 = FM_SWB_PWR_EN_R1_BUF ; 2 = FM_SWB_PWR_EN_R_BUF
R3516  Q_RES  0 5% CHIP  pkg 0402LF  page 227 : 1 = GPU_BASE_ID0 ; 2 = GPU_BASE_ID0_R
R3517  Q_RES  0 5% CHIP  pkg 0402LF  page 227 : 1 = GPU_PEX_STRAP1 ; 2 = GPU_PEX_STRAP1_R
R3518  Q_RES  0 5% CHIP  pkg 0402LF  page 227 : 1 = GPU_PEX_STRAP0 ; 2 = GPU_PEX_STRAP0_R
R3519  Q_RES  4.7K 5% CHIP  pkg 0402LF  page 238 : 1 = P3V3_OCP_V3_2 ; 2 = SMB_OCP_V3_2_3V3AUX_BUF_SCL
R3520  Q_RES  4.7K 5% CHIP  pkg 0402LF  page 238 : 1 = P3V3_OCP_V3_2 ; 2 = SMB_OCP_V3_2_3V3AUX_BUF_SDA
R3521  Q_RES  54.9K 1% CHIP  pkg 0402LF  page 234 : 1 = P3V3_AUX ; 2 = SMB_2_BMC_GPU_BUF_R_SCL
R3522  Q_RES  54.9K 1% CHIP  pkg 0402LF  page 234 : 1 = P3V3_AUX ; 2 = SMB_2_BMC_GPU_BUF_R_SDA
R3523  Q_RES  54.9K 1% CHIP  pkg 0402LF  page 234 : 1 = P3V3_AUX ; 2 = SMB_1_BMC_GPU_BUF_R_SCL
R3524  Q_RES  54.9K 1% CHIP  pkg 0402LF  page 234 : 1 = P3V3_AUX ; 2 = SMB_1_BMC_GPU_BUF_R_SDA
R3525  Q_RES  54.9K 1% CHIP  pkg 0402LF  page 147 : 1 = P3V3_AUX ; 2 = GPU_FPGA_EROT_FATALERR_N
R3526  Q_RES  0 5% CHIP  pkg 0402LF  page 231 : 1 = SMB_PCIE0_3V3AUX_SCL_R5 ; 2 = SMB_SENSOR_E1S_3V3AUX_SCL
R3527  Q_RES  0 5% CHIP  pkg 0402LF  page 231 : 1 = SMB_PCIE0_3V3AUX_SDA_R5 ; 2 = SMB_SENSOR_E1S_3V3AUX_SDA
R3529  Q_RES  10K 1% CHIP  pkg 0402LF  page 194 : 1 = P3V3_AUX ; 2 = SMB_PCIE_E1S_ISO_EN_R
R3530  Q_RES  4.7K 5% CHIP  pkg 0402LF  page 194 : 1 = P3V3_E1S_0 ; 2 = SMB_E1S_3V3AUX_ISO_SCL_R
R3531  Q_RES  200K 1% EMPTY  pkg 0402LF  page 194 : 1 = SMB_PCIE_E1S_ISO_EN ; 2 = SMB_PCIE_E1S_ISO_EN_R
R3532  Q_RES  4.7K 5% CHIP  pkg 0402LF  page 194 : 1 = P3V3_E1S_0 ; 2 = SMB_E1S_3V3AUX_ISO_SDA_R
R3533  Q_RES  33.2 1% CHIP  pkg 0402LF  page 194 : 1 = SMB_E1S_3V3AUX_ISO_SCL_R ; 2 = SMB_E1S_3V3AUX_ISO_SCL
R3534  Q_RES  33.2 1% CHIP  pkg 0402LF  page 194 : 1 = SMB_E1S_3V3AUX_ISO_SDA_R ; 2 = SMB_E1S_3V3AUX_ISO_SDA
R3535  Q_RES  2.2K 5% CHIP  pkg 0402LF  page 231 : 1 = P3V3_AUX ; 2 = SMB_SENSOR_E1S_3V3AUX_SCL
R3536  Q_RES  2.2K 5% CHIP  pkg 0402LF  page 231 : 1 = P3V3_AUX ; 2 = SMB_SENSOR_E1S_3V3AUX_SDA
R3553  Q_RES  33.2 1% CHIP  pkg 0402LF  page 170 : 1 = SMB_LM75_3_3V3AUX_SCL ; 2 = SMB_LM75_3_3V3AUX_SCL_R1
R3554  Q_RES  33.2 1% CHIP  pkg 0402LF  page 170 : 1 = SMB_LM75_3_3V3AUX_SDA ; 2 = SMB_LM75_3_3V3AUX_SDA_R1
R3559  Q_RES  0 5% CHIP  pkg 0402LF  page 172 : 1 = OCP_V3_2_P3V3_ADC_ALERT_R ; 2 = OCP_V3_2_P3V3_ADC_ALERT
R3560  Q_RES  0 5% CHIP  pkg 0402LF  page 172 : 1 = M2_0_P3V3_ADC_ALERT_R ; 2 = M2_0_P3V3_ADC_ALERT
R3561  Q_RES  0 5% CHIP  pkg 0402LF  page 172 : 1 = P12V_SCM_ADC_ALERT_R ; 2 = P12V_SCM_ADC_ALERT
R3563  Q_RES  0 5% CHIP  pkg 0402LF  page 171 : 1 = OCP_SFF_P3V3_ADC_ALERT_R ; 2 = OCP_SFF_P3V3_ADC_ALERT
R3568  Q_RES  33.2 1% CHIP  pkg 0402LF  page 172 : 1 = SMB_INA230_3_3V3AUX_SCL_R ; 2 = SMB_INA230_3_3V3AUX_SCL_R1
R3569  Q_RES  33.2 1% CHIP  pkg 0402LF  page 172 : 1 = SMB_INA230_3_3V3AUX_SDA_R ; 2 = SMB_INA230_3_3V3AUX_SDA_R1
R3570  Q_RES  10 1% CHIP  pkg 0402LF  page 172 : 1 = P3V3_OCP_V3_2_R ; 2 = VSENSE_P12V_INA230_3_INP
R3571  Q_RES  10 1% CHIP  pkg 0402LF  page 172 : 1 = P3V3_OCP_V3_2 ; 2 = VSENSE_P12V_INA230_3_INN
R3572  Q_RES  33.2 1% CHIP  pkg 0402LF  page 172 : 1 = SMB_INA230_4_3V3AUX_SCL_R ; 2 = SMB_INA230_4_3V3AUX_SCL_R1
R3573  Q_RES  33.2 1% CHIP  pkg 0402LF  page 172 : 1 = SMB_INA230_4_3V3AUX_SDA_R ; 2 = SMB_INA230_4_3V3AUX_SDA_R1
R3574  Q_RES  10 1% CHIP  pkg 0402LF  page 172 : 1 = P3V3 ; 2 = VSENSE_P12V_INA230_4_INP
R3575  Q_RES  10 1% CHIP  pkg 0402LF  page 172 : 1 = P3V3_M2_0 ; 2 = VSENSE_P12V_INA230_4_INN
R3576  Q_RES  33.2 1% CHIP  pkg 0402LF  page 172 : 1 = SMB_INA230_5_3V3AUX_SCL_R ; 2 = SMB_INA230_5_3V3AUX_SCL_R1
R3577  Q_RES  33.2 1% CHIP  pkg 0402LF  page 172 : 1 = SMB_INA230_5_3V3AUX_SDA_R ; 2 = SMB_INA230_5_3V3AUX_SDA_R1
R3578  Q_RES  10 1% CHIP  pkg 0402LF  page 172 : 1 = P12V_SCM_R ; 2 = VSENSE_P12V_INA230_5_INP
R3579  Q_RES  10 1% CHIP  pkg 0402LF  page 172 : 1 = P12V_SCM ; 2 = VSENSE_P12V_INA230_5_INN
R3580  Q_RES  0 5% CHIP  pkg 0402LF  page 231 : 1 = SMB_INA230_3V3AUX_SCL_R ; 2 = SMB_INA230_3V3AUX_SCL
R3581  Q_RES  0 5% CHIP  pkg 0402LF  page 231 : 1 = SMB_INA230_3V3AUX_SDA_R ; 2 = SMB_INA230_3V3AUX_SDA
R3582  Q_RES  2.2K 5% CHIP  pkg 0402LF  page 231 : 1 = P3V3_AUX ; 2 = SMB_IOEXP_3V3AUX_SCL
R3583  Q_RES  2.2K 5% CHIP  pkg 0402LF  page 231 : 1 = P3V3_AUX ; 2 = SMB_IOEXP_3V3AUX_SDA
R3586  Q_RES  33.2 1% CHIP  pkg 0402LF  page 232 : 1 = SMB_INA230_3V3AUX_SCL ; 2 = SMB_INA230_1_3V3AUX_SCL_R
R3587  Q_RES  33.2 1% CHIP  pkg 0402LF  page 232 : 1 = SMB_INA230_3V3AUX_SDA ; 2 = SMB_INA230_1_3V3AUX_SDA_R
R3588  Q_RES  33.2 1% CHIP  pkg 0402LF  page 232 : 1 = SMB_INA230_3V3AUX_SCL ; 2 = SMB_INA230_2_3V3AUX_SCL_R
R3589  Q_RES  33.2 1% CHIP  pkg 0402LF  page 232 : 1 = SMB_INA230_3V3AUX_SDA ; 2 = SMB_INA230_2_3V3AUX_SDA_R
R3590  Q_RES  33.2 1% CHIP  pkg 0402LF  page 232 : 1 = SMB_INA230_3V3AUX_SCL ; 2 = SMB_INA230_3_3V3AUX_SCL_R
R3591  Q_RES  33.2 1% CHIP  pkg 0402LF  page 232 : 1 = SMB_INA230_3V3AUX_SDA ; 2 = SMB_INA230_3_3V3AUX_SDA_R
R3592  Q_RES  33.2 1% CHIP  pkg 0402LF  page 232 : 1 = SMB_INA230_3V3AUX_SCL ; 2 = SMB_INA230_5_3V3AUX_SCL_R
R3593  Q_RES  33.2 1% CHIP  pkg 0402LF  page 232 : 1 = SMB_INA230_3V3AUX_SDA ; 2 = SMB_INA230_5_3V3AUX_SDA_R
R3594  Q_RES  33.2 1% CHIP  pkg 0402LF  page 232 : 1 = SMB_INA230_3V3AUX_SCL ; 2 = SMB_INA230_4_3V3AUX_SCL_R
R3595  Q_RES  33.2 1% CHIP  pkg 0402LF  page 232 : 1 = SMB_INA230_3V3AUX_SDA ; 2 = SMB_INA230_4_3V3AUX_SDA_R
R3600  Q_RES  33.2 1% CHIP  pkg 0402LF  page 171 : 1 = SMB_INA230_1_3V3AUX_SCL_R ; 2 = SMB_INA230_1_3V3AUX_SCL_R1
R3601  Q_RES  33.2 1% CHIP  pkg 0402LF  page 171 : 1 = SMB_INA230_1_3V3AUX_SDA_R ; 2 = SMB_INA230_1_3V3AUX_SDA_R1
R3602  Q_RES  10 1% CHIP  pkg 0402LF  page 171 : 1 = P3V3_OCP_SFF_R ; 2 = VSENSE_P3V3_INA230_1_INP
R3603  Q_RES  10 1% CHIP  pkg 0402LF  page 171 : 1 = P3V3_OCP_SFF ; 2 = VSENSE_P3V3_INA230_1_INN
R3608  Q_RES  4.7K 1% CHIP  pkg 0402LF  page 172 : 1 = GND ; 2 = INA230_3_A1
R3609  Q_RES  4.7K 1% EMPTY  pkg 0402LF  page 172 : 1 = GND ; 2 = INA230_3_A0
R3610  Q_RES  4.7K 1% EMPTY  pkg 0402LF  page 172 : 1 = GND ; 2 = INA230_4_A1
R3611  Q_RES  4.7K 1% CHIP  pkg 0402LF  page 172 : 1 = GND ; 2 = INA230_4_A0
R3612  Q_RES  4.7K 1% EMPTY  pkg 0402LF  page 172 : 1 = GND ; 2 = INA230_5_A1
R3613  Q_RES  4.7K 1% EMPTY  pkg 0402LF  page 172 : 1 = GND ; 2 = INA230_5_A0
R3616  Q_RES  4.7K 1% CHIP  pkg 0402LF  page 171 : 1 = GND ; 2 = INA230_1_A1
R3617  Q_RES  4.7K 1% EMPTY  pkg 0402LF  page 171 : 1 = GND ; 2 = INA230_1_A0
R3620  Q_RES  0 5% CHIP  pkg 0402LF  page 172 : 1 = INA230_3_A0 ; 2 = SMB_INA230_3_3V3AUX_SCL_R1
R3621  Q_RES  4.7K 1% EMPTY  pkg 0402LF  page 172 : 1 = P3V3_AUX ; 2 = INA230_4_A0
R3622  Q_RES  4.7K 1% CHIP  pkg 0402LF  page 172 : 1 = P3V3_AUX ; 2 = INA230_5_A0
R3623  Q_RES  4.7K 1% CHIP  pkg 0402LF  page 172 : 1 = P3V3_AUX ; 2 = INA230_4_A1
R3624  Q_RES  4.7K 1% CHIP  pkg 0402LF  page 172 : 1 = P3V3_AUX ; 2 = INA230_5_A1
R3627  Q_RES  4.7K 1% CHIP  pkg 0402LF  page 171 : 1 = P3V3_AUX ; 2 = INA230_1_A0
R3628  Q_RES  4.7K 1% EMPTY  pkg 0402LF  page 171 : 1 = P3V3_AUX ; 2 = INA230_1_A1
R3630  Q_RES  0 5% CHIP  pkg 0402LF  page 163 : 1 = HP_LVC3_OCP_V3_2_EN ; 2 = P12V_OCP_V3_2_EN_2_R3
R3631  Q_RES  0 5% EMPTY  pkg 0402LF  page 163 : 1 = HP_LVC3_OCP_V3_2_EN ; 2 = P3V3_OCP_EN_2
R3633  Q_RES  0.01 1% CHIP  pkg 2512LF  page 172 : 1 = P3V3_OCP_V3_2 ; 2 = P3V3_OCP_V3_2_R
R3634  Q_RES  0.01 1% CHIP  pkg 2512LF  page 172 : 1 = P3V3_M2_0 ; 2 = P3V3
R3635  Q_RES  0.01 1% CHIP  pkg 2512LF  page 172 : 1 = P12V_SCM ; 2 = P12V_SCM_R
R3636  Q_RES  0 5% CHIP  pkg 0402LF  page 206 : 1 = OCP_SFF_CLK_OE_N ; 2 = FM_DB2000_11_OE_N
R3637  Q_RES  0 5% CHIP  pkg 0402LF  page 206 : 1 = OCP_SFF_CLK_OE_N ; 2 = FM_DB2000_12_OE_N
R3638  Q_RES  10K 1% CHIP  pkg 0402LF  page 208 : 1 = P3V3_AUX ; 2 = CK440Q_OE_1
R3639  Q_RES  10K 1% CHIP  pkg 0402LF  page 208 : 1 = P3V3_AUX ; 2 = CK440Q_OE_2
R3640  Q_RES  10K 1% CHIP  pkg 0402LF  page 208 : 1 = P3V3_AUX ; 2 = CK440Q_OE_3
R3641  Q_RES  10K 1% CHIP  pkg 0402LF  page 208 : 1 = P3V3_AUX ; 2 = CK440Q_OE_4
R3642  Q_RES  10K 1% CHIP  pkg 0402LF  page 208 : 1 = P3V3_AUX ; 2 = CK440Q_OE_5
R3643  Q_RES  10K 1% CHIP  pkg 0402LF  page 208 : 1 = P3V3_AUX ; 2 = CK440Q_OE_6
R3645  Q_RES  0.01 1% CHIP  pkg 2512LF  page 171 : 1 = P3V3_OCP_SFF ; 2 = P3V3_OCP_SFF_R
R3651  Q_RES  0 5% CHIP  pkg 0402LF  page 152 : 1 = USB2_P0_R_DP ; 2 = USB2_HOST_BMC_B_DP
R3652  Q_RES  0 5% CHIP  pkg 0402LF  page 152 : 1 = USB2_P0_R_DN ; 2 = USB2_HOST_BMC_B_DN
R3653  Q_RES  680 1% CHIP  pkg 0402LF  page 152 : 1 = USB_HUB_RREF ; 2 = GND
R3654  Q_RES  33.2 1% CHIP  pkg 0402LF  page 152 : 1 = RST_USB_HUB_N ; 2 = RST_USB_HUB_R_N
R3655  Q_RES  0 5% CHIP  pkg 0402LF  page 152 : 1 = P3V3_AUX ; 2 = P3V3_AUX_USB_HUB
R3656  Q_RES  10K 1% EMPTY  pkg 0402LF  page 152 : 1 = P3V3_AUX ; 2 = USB_HUB_OVCUR1
R3657  Q_RES  10K 1% EMPTY  pkg 0402LF  page 152 : 1 = P3V3_AUX ; 2 = USB_HUB_OVCUR2
R3658  Q_RES  10K 1% EMPTY  pkg 0402LF  page 152 : 1 = P3V3_AUX ; 2 = USB_HUB_OVCUR3
R3659  Q_RES  10K 1% EMPTY  pkg 0402LF  page 152 : 1 = P3V3_AUX ; 2 = USB_HUB_OVCUR4
R3660  Q_RES  10K 1% CHIP  pkg 0402LF  page 152 : 1 = P3V3_AUX ; 2 = RST_USB_HUB_R_N
R3661  Q_RES  47K 0.1% EMPTY  pkg 0402LF  page 152 : 1 = GND ; 2 = RST_USB_HUB_R_N
R3662  Q_RES  0 5% CHIP  pkg 0402LF  page 152 : 1 = P3V3_AUX_USB_HUB ; 2 = USB_HUB_DVDD
R3663  Q_RES  10K 1% CHIP  pkg 0402LF  page 152 : 1 = P3V3_AUX ; 2 = USB_HUB_PSELF
R3664  Q_RES  10K 1% EMPTY  pkg 0402LF  page 152 : 1 = USB_HUB_PSELF ; 2 = GND
R3665  Q_RES  100K 1% CHIP  pkg 0402LF  page 152 : 1 = USB_HUB_PGANG ; 2 = GND
R3666  Q_RES  0 5% CHIP  pkg 0402LF  page 152 : 1 = USB_HUB_TEST ; 2 = GND
R3667  Q_RES  1K 1% EMPTY  pkg 0402LF  page 250 : 1 = P3V3_AUX ; 2 = ADC128_A1
R3668  Q_RES  1K 1% CHIP  pkg 0402LF  page 250 : 1 = ADC128_A1 ; 2 = GND
R3669  Q_RES  1K 1% EMPTY  pkg 0402LF  page 250 : 1 = P3V3_AUX ; 2 = ADC128_A0
R3670  Q_RES  1K 1% CHIP  pkg 0402LF  page 250 : 1 = ADC128_A0 ; 2 = GND
R3671  Q_RES  0 5% CHIP  pkg 0402LF  page 250 : 1 = SMB_VR_3V3AUX_SDA_R1 ; 2 = SMB_SEN_TIC_3V3AUX_SDA
R3672  Q_RES  0 5% CHIP  pkg 0402LF  page 250 : 1 = SMB_VR_3V3AUX_SCL_R1 ; 2 = SMB_SEN_TIC_3V3AUX_SCL
R3679  Q_RES  0 5% EMPTY  pkg 0402LF  page 250 : 1 = P12V_AUX_ADC ; 2 = P12V_AUX_ADC_MAM
R3680  Q_RES  0 5% CHIP  pkg 0402LF  page 250 : 1 = P12V_AUX_ADC ; 2 = P12V_AUX_ADC_TIC
R3681  Q_RES  0 5% EMPTY  pkg 0402LF  page 250 : 1 = P3V3_AUX_ADC ; 2 = P3V3_AUX_ADC_MAM
R3682  Q_RES  0 5% CHIP  pkg 0402LF  page 250 : 1 = P3V3_AUX_ADC ; 2 = P3V3_AUX_ADC_TIC
R3683  Q_RES  0 5% EMPTY  pkg 0402LF  page 250 : 1 = P3V3_ADC ; 2 = P3V3_ADC_MAM
R3684  Q_RES  0 5% CHIP  pkg 0402LF  page 250 : 1 = P3V3_ADC ; 2 = P3V3_ADC_TIC
R3685  Q_RES  0 5% EMPTY  pkg 0402LF  page 250 : 1 = P5V_ADC ; 2 = P5V_ADC_MAM
R3686  Q_RES  0 5% CHIP  pkg 0402LF  page 250 : 1 = P5V_ADC ; 2 = P5V_ADC_TIC
R3687  Q_RES  0 5% EMPTY  pkg 0402LF  page 250 : 1 = P1V581_PDB_ADC ; 2 = P3V3_PDB_AUX_ADC_MAM
R3688  Q_RES  0 5% CHIP  pkg 0402LF  page 250 : 1 = P1V581_PDB_ADC ; 2 = P3V3_PDB_AUX_ADC_TIC
R3689  Q_RES  4.7K 1% EMPTY  pkg 0402LF  page 250 : 1 = P3V3_ADC128_VCC ; 2 = ADC128_VREF
R3690  Q_RES  4.7K 1% EMPTY  pkg 0402LF  page 250 : 1 = ADC128_VREF ; 2 = GND
R3703  Q_RES  10K 1% EMPTY  pkg 0402LF  page 233 : 1 = P3V3_AUX ; 2 = PCA9548_PCIE0_ADDR2
R3704  Q_RES  1K 1% CHIP  pkg 0402LF  page 233 : 1 = PCA9548_PCIE0_ADDR2 ; 2 = GND
R3705  Q_RES  10K 1% EMPTY  pkg 0402LF  page 233 : 1 = P3V3_AUX ; 2 = RST_SMB_SWITCH_N
R3706  Q_RES  10K 1% EMPTY  pkg 0402LF  page 233 : 1 = P3V3_AUX ; 2 = PCA9548_PCIE0_ADDR1
R3707  Q_RES  1K 1% CHIP  pkg 0402LF  page 233 : 1 = PCA9548_PCIE0_ADDR1 ; 2 = GND
R3708  Q_RES  10K 1% EMPTY  pkg 0402LF  page 233 : 1 = P3V3_AUX ; 2 = PCA9548_PCIE0_ADDR0
R3709  Q_RES  1K 1% CHIP  pkg 0402LF  page 233 : 1 = PCA9548_PCIE0_ADDR0 ; 2 = GND
R3710  Q_RES  0 5% CHIP  pkg 0402LF  page 233 : 1 = RST_SMB_SWITCH_N ; 2 = PU_RST_SMB_PCIE2_N
R3711  Q_RES  33.2 1% CHIP  pkg 0402LF  page 233 : 1 = SMB_VR_SENSOR_3V3AUX_SCL ; 2 = SMB_VR_SENSOR_3V3AUX_SCL_R
R3712  Q_RES  33.2 1% CHIP  pkg 0402LF  page 233 : 1 = SMB_VR_SENSOR_3V3AUX_SDA ; 2 = SMB_VR_SENSOR_3V3AUX_SDA_R
R3713  Q_RES  0 5% CHIP  pkg 0402LF  page 233 : 1 = SMB_VR_3V3AUX_SCL_R6 ; 2 = SMB_VR_3V3AUX_SCL
R3714  Q_RES  0 5% CHIP  pkg 0402LF  page 233 : 1 = SMB_VR_3V3AUX_SDA_R6 ; 2 = SMB_VR_3V3AUX_SDA
R3715  Q_RES  0 5% CHIP  pkg 0402LF  page 233 : 1 = SMB_LM75_0_3V3AUX_SCL_R ; 2 = SMB_LM75_0_3V3AUX_SCL
R3716  Q_RES  0 5% CHIP  pkg 0402LF  page 233 : 1 = SMB_LM75_0_3V3AUX_SDA_R ; 2 = SMB_LM75_0_3V3AUX_SDA
R3717  Q_RES  0 5% CHIP  pkg 0402LF  page 233 : 1 = SMB_LM75_1_3V3AUX_SCL_R ; 2 = SMB_LM75_1_3V3AUX_SCL
R3718  Q_RES  0 5% CHIP  pkg 0402LF  page 233 : 1 = SMB_LM75_1_3V3AUX_SDA_R ; 2 = SMB_LM75_1_3V3AUX_SDA
R3719  Q_RES  0 5% CHIP  pkg 0402LF  page 233 : 1 = SMB_LM75_2_3V3AUX_SCL_R ; 2 = SMB_LM75_2_3V3AUX_SCL
R3720  Q_RES  0 5% CHIP  pkg 0402LF  page 233 : 1 = SMB_LM75_2_3V3AUX_SDA_R ; 2 = SMB_LM75_2_3V3AUX_SDA
R3721  Q_RES  0 5% CHIP  pkg 0402LF  page 233 : 1 = SMB_LM75_3_3V3AUX_SCL_R ; 2 = SMB_LM75_3_3V3AUX_SCL
R3722  Q_RES  0 5% CHIP  pkg 0402LF  page 233 : 1 = SMB_LM75_3_3V3AUX_SDA_R ; 2 = SMB_LM75_3_3V3AUX_SDA
R3723  Q_RES  2.2K 5% CHIP  pkg 0402LF  page 233 : 1 = P3V3_AUX ; 2 = SMB_VR_3V3AUX_SCL
R3724  Q_RES  2.2K 5% CHIP  pkg 0402LF  page 233 : 1 = P3V3_AUX ; 2 = SMB_VR_3V3AUX_SDA
R3725  Q_RES  2.2K 5% CHIP  pkg 0402LF  page 233 : 1 = P3V3_AUX ; 2 = SMB_LM75_0_3V3AUX_SCL
R3726  Q_RES  2.2K 5% CHIP  pkg 0402LF  page 233 : 1 = P3V3_AUX ; 2 = SMB_LM75_0_3V3AUX_SDA
R3727  Q_RES  2.2K 5% CHIP  pkg 0402LF  page 233 : 1 = P3V3_AUX ; 2 = SMB_LM75_1_3V3AUX_SCL
R3728  Q_RES  2.2K 5% CHIP  pkg 0402LF  page 233 : 1 = P3V3_AUX ; 2 = SMB_LM75_1_3V3AUX_SDA
R3729  Q_RES  2.2K 5% CHIP  pkg 0402LF  page 233 : 1 = P3V3_AUX ; 2 = SMB_LM75_2_3V3AUX_SCL
R3730  Q_RES  2.2K 5% CHIP  pkg 0402LF  page 233 : 1 = P3V3_AUX ; 2 = SMB_LM75_2_3V3AUX_SDA
R3731  Q_RES  2.2K 5% CHIP  pkg 0402LF  page 233 : 1 = P3V3_AUX ; 2 = SMB_LM75_3_3V3AUX_SCL
R3732  Q_RES  2.2K 5% CHIP  pkg 0402LF  page 233 : 1 = P3V3_AUX ; 2 = SMB_LM75_3_3V3AUX_SDA
